(kicad_pcb
	(version 20260206)
	(generator "pcbnew")
	(generator_version "10.0")
	(general
		(thickness 1.6)
		(legacy_teardrops no)
	)
	(paper "A4")
	(title_block
		(title "04192023_DAF0TMB3IC0_F0TG_MB_C_brd_V02_OCP.brd")
		(comment 1 "Grand Teton / footprint 2783 of 8354 (U26), pads 2219-2333 of 6102")
	)
	(layers
		(0 "F.Cu" signal "TOP")
		(4 "In1.Cu" signal "GND")
		(6 "In2.Cu" signal "IN1")
		(8 "In3.Cu" signal "GND1")
		(10 "In4.Cu" signal "IN2")
		(12 "In5.Cu" signal "GND2")
		(14 "In6.Cu" signal "IN3")
		(16 "In7.Cu" signal "GND3")
		(18 "In8.Cu" signal "VCC")
		(20 "In9.Cu" signal "VCC1")
		(22 "In10.Cu" signal "GND4")
		(24 "In11.Cu" signal "IN4")
		(26 "In12.Cu" signal "GND5")
		(28 "In13.Cu" signal "IN5")
		(30 "In14.Cu" signal "GND6")
		(32 "In15.Cu" signal "IN6")
		(34 "In16.Cu" signal "GND7")
		(2 "B.Cu" signal "BOTTOM")
		(9 "F.Adhes" user "F.Adhesive")
		(11 "B.Adhes" user "B.Adhesive")
		(13 "F.Paste" user "Package Geometry/Pastemask Top")
		(15 "B.Paste" user "Package Geometry/Pastemask Bottom")
		(5 "F.SilkS" user "Ref Des/Silkscreen Top")
		(7 "B.SilkS" user "Ref Des/Silkscreen Bottom")
		(1 "F.Mask" user "Board Geometry/Soldermask Top")
		(3 "B.Mask" user "Board Geometry/Soldermask Bottom")
		(17 "Dwgs.User" user "User.Drawings")
		(19 "Cmts.User" user "User.Comments")
		(21 "Eco1.User" user "User.Eco1")
		(23 "Eco2.User" user "User.Eco2")
		(25 "Edge.Cuts" user "Board Geometry/Outline")
		(27 "Margin" user)
		(31 "F.CrtYd" user "Package Geometry/Place Bound Top")
		(29 "B.CrtYd" user "Package Geometry/Place Bound Bottom")
		(35 "F.Fab" user "Ref Des/Assembly Top")
		(33 "B.Fab" user "Ref Des/Assembly Bottom")
	)
	(footprint ""
		(layer "F.Cu")
		(at 111.927894 -258.880356 180)
		(property "Reference" "U26"
			(at -45.05579 -61.794136 0)
			(unlocked yes)
			(layer "F.SilkS")
			(effects
				(font
					(size 0.7874 0.5842)
					(thickness 0.1524)
				)
			)
		)
		(property "Value" ""
			(at 0 0 180)
			(layer "F.Fab")
			(effects
				(font
					(size 1.27 1.27)
				)
			)
		)
		(duplicate_pad_numbers_are_jumpers no)
		(pad "BN62" smd circle
			(at 21.940012 7.649972 180)
			(size 0.450088 0.450088)
			(layers "F.Cu" "F.Mask" "F.Paste")
			(net "M_B_CPU1_SA_RSP<0>")
		)
		(pad "BN63" smd circle
			(at 22.880066 7.649972 180)
			(size 0.450088 0.450088)
			(layers "F.Cu" "F.Mask" "F.Paste")
			(net "GND")
		)
		(pad "BN64" smd circle
			(at 23.82012 7.649972 180)
			(size 0.450088 0.450088)
			(layers "F.Cu" "F.Mask" "F.Paste")
			(net "M_B_CPU1_SB_CS_N<1>")
		)
		(pad "BN65" smd circle
			(at 24.75992 7.649972 180)
			(size 0.450088 0.450088)
			(layers "F.Cu" "F.Mask" "F.Paste")
			(net "GND")
		)
		(pad "BN66" smd circle
			(at 25.699974 7.649972 180)
			(size 0.450088 0.450088)
			(layers "F.Cu" "F.Mask" "F.Paste")
			(net "M_F_CPU1_SA_RSP<0>")
		)
		(pad "BN67" smd circle
			(at 26.640028 7.649972 180)
			(size 0.450088 0.450088)
			(layers "F.Cu" "F.Mask" "F.Paste")
			(net "M_F_CPU1_SB_CS_N<1>")
		)
		(pad "BN68" smd circle
			(at 27.580082 7.649972 180)
			(size 0.450088 0.450088)
			(layers "F.Cu" "F.Mask" "F.Paste")
			(net "GND")
		)
		(pad "BN69" smd circle
			(at 28.519882 7.649972 180)
			(size 0.450088 0.450088)
			(layers "F.Cu" "F.Mask" "F.Paste")
			(net "M_E_CPU1_SA_RSP<0>")
		)
		(pad "BN70" smd circle
			(at 29.459936 7.649972 180)
			(size 0.450088 0.450088)
			(layers "F.Cu" "F.Mask" "F.Paste")
			(net "GND")
		)
		(pad "BN71" smd circle
			(at 30.39999 7.649972 180)
			(size 0.450088 0.450088)
			(layers "F.Cu" "F.Mask" "F.Paste")
			(net "M_E_CPU1_SB_CS_N<1>")
		)
		(pad "BN72" smd circle
			(at 31.340044 7.649972 180)
			(size 0.450088 0.450088)
			(layers "F.Cu" "F.Mask" "F.Paste")
			(net "GND")
		)
		(pad "BN73" smd circle
			(at 32.280098 7.649972 180)
			(size 0.450088 0.450088)
			(layers "F.Cu" "F.Mask" "F.Paste")
			(net "M_A_CPU1_SA_RSP<0>")
		)
		(pad "BN74" smd circle
			(at 33.219898 7.649972 180)
			(size 0.450088 0.450088)
			(layers "F.Cu" "F.Mask" "F.Paste")
			(net "M_A_CPU1_SB_CS_N<1>")
		)
		(pad "BN75" smd circle
			(at 34.159952 7.649972 180)
			(size 0.450088 0.450088)
			(layers "F.Cu" "F.Mask" "F.Paste")
			(net "GND")
		)
		(pad "BP2" smd circle
			(at -33.990026 8.459978 180)
			(size 0.450088 0.450088)
			(layers "F.Cu" "F.Mask" "F.Paste")
			(net "M_G_CPU1_SB_RSP<0>")
		)
		(pad "BP3" smd circle
			(at -33.049972 8.459978 180)
			(size 0.450088 0.450088)
			(layers "F.Cu" "F.Mask" "F.Paste")
			(net "GND")
		)
		(pad "BP4" smd circle
			(at -32.109918 8.459978 180)
			(size 0.450088 0.450088)
			(layers "F.Cu" "F.Mask" "F.Paste")
			(net "Net_2042")
		)
		(pad "BP5" smd circle
			(at -31.170118 8.459978 180)
			(size 0.450088 0.450088)
			(layers "F.Cu" "F.Mask" "F.Paste")
			(net "GND")
		)
		(pad "BP6" smd circle
			(at -30.230064 8.459978 180)
			(size 0.450088 0.450088)
			(layers "F.Cu" "F.Mask" "F.Paste")
			(net "M_K_CPU1_SB_RSP<0>")
		)
		(pad "BP7" smd circle
			(at -29.29001 8.459978 180)
			(size 0.450088 0.450088)
			(layers "F.Cu" "F.Mask" "F.Paste")
			(net "Net_2191")
		)
		(pad "BP8" smd circle
			(at -28.349956 8.459978 180)
			(size 0.450088 0.450088)
			(layers "F.Cu" "F.Mask" "F.Paste")
			(net "GND")
		)
		(pad "BP9" smd circle
			(at -27.409902 8.459978 180)
			(size 0.450088 0.450088)
			(layers "F.Cu" "F.Mask" "F.Paste")
			(net "M_L_CPU1_SB_RSP<0>")
		)
		(pad "BP10" smd circle
			(at -26.470102 8.459978 180)
			(size 0.450088 0.450088)
			(layers "F.Cu" "F.Mask" "F.Paste")
			(net "GND")
		)
		(pad "BP11" smd circle
			(at -25.530048 8.459978 180)
			(size 0.450088 0.450088)
			(layers "F.Cu" "F.Mask" "F.Paste")
			(net "Net_2183")
		)
		(pad "BP12" smd circle
			(at -24.589994 8.459978 180)
			(size 0.450088 0.450088)
			(layers "F.Cu" "F.Mask" "F.Paste")
			(net "GND")
		)
		(pad "BP13" smd circle
			(at -23.64994 8.459978 180)
			(size 0.450088 0.450088)
			(layers "F.Cu" "F.Mask" "F.Paste")
			(net "M_H_CPU1_SB_RSP<0>")
		)
		(pad "BP14" smd circle
			(at -22.709886 8.459978 180)
			(size 0.450088 0.450088)
			(layers "F.Cu" "F.Mask" "F.Paste")
			(net "Net_2050")
		)
		(pad "BP15" smd circle
			(at -21.770086 8.459978 180)
			(size 0.450088 0.450088)
			(layers "F.Cu" "F.Mask" "F.Paste")
			(net "GND")
		)
		(pad "BP16" smd circle
			(at -20.830032 8.459978 180)
			(size 0.450088 0.450088)
			(layers "F.Cu" "F.Mask" "F.Paste")
			(net "M_J_CPU1_SB_RSP<0>")
		)
		(pad "BP17" smd circle
			(at -19.889978 8.459978 180)
			(size 0.450088 0.450088)
			(layers "F.Cu" "F.Mask" "F.Paste")
			(net "GND")
		)
		(pad "BP18" smd circle
			(at -18.949924 8.459978 180)
			(size 0.450088 0.450088)
			(layers "F.Cu" "F.Mask" "F.Paste")
			(net "Net_2066")
		)
		(pad "BP19" smd circle
			(at -18.010124 8.459978 180)
			(size 0.450088 0.450088)
			(layers "F.Cu" "F.Mask" "F.Paste")
			(net "GND")
		)
		(pad "BP20" smd circle
			(at -17.07007 8.459978 180)
			(size 0.450088 0.450088)
			(layers "F.Cu" "F.Mask" "F.Paste")
			(net "M_I_CPU1_SB_RSP<0>")
		)
		(pad "BP21" smd circle
			(at -16.130016 8.459978 180)
			(size 0.450088 0.450088)
			(layers "F.Cu" "F.Mask" "F.Paste")
			(net "Net_2058")
		)
		(pad "BP22" smd circle
			(at -15.189962 8.459978 180)
			(size 0.450088 0.450088)
			(layers "F.Cu" "F.Mask" "F.Paste")
			(net "PVDD11_S3_P1")
		)
		(pad "BP23" smd circle
			(at -14.249908 8.459978 180)
			(size 0.450088 0.450088)
			(layers "F.Cu" "F.Mask" "F.Paste")
			(net "GND")
		)
		(pad "BP24" smd circle
			(at -13.310108 8.459978 180)
			(size 0.450088 0.450088)
			(layers "F.Cu" "F.Mask" "F.Paste")
			(net "PVDDCR_CPU1_P1")
		)
		(pad "BP25" smd circle
			(at -12.370054 8.459978 180)
			(size 0.450088 0.450088)
			(layers "F.Cu" "F.Mask" "F.Paste")
			(net "GND")
		)
		(pad "BP26" smd circle
			(at -11.43 8.459978 180)
			(size 0.450088 0.450088)
			(layers "F.Cu" "F.Mask" "F.Paste")
			(net "PVDDCR_CPU1_P1")
		)
		(pad "BP27" smd circle
			(at -10.489946 8.459978 180)
			(size 0.450088 0.450088)
			(layers "F.Cu" "F.Mask" "F.Paste")
			(net "GND")
		)
		(pad "BP28" smd circle
			(at -9.549892 8.459978 180)
			(size 0.450088 0.450088)
			(layers "F.Cu" "F.Mask" "F.Paste")
			(net "PVDDCR_CPU1_P1")
		)
		(pad "BP29" smd circle
			(at -8.610092 8.459978 180)
			(size 0.450088 0.450088)
			(layers "F.Cu" "F.Mask" "F.Paste")
			(net "GND")
		)
		(pad "BP30" smd circle
			(at -7.670038 8.459978 180)
			(size 0.450088 0.450088)
			(layers "F.Cu" "F.Mask" "F.Paste")
			(net "PVDDCR_CPU1_P1")
		)
		(pad "BP31" smd circle
			(at -6.729984 8.459978 180)
			(size 0.450088 0.450088)
			(layers "F.Cu" "F.Mask" "F.Paste")
			(net "GND")
		)
		(pad "BP32" smd circle
			(at -5.78993 8.459978 180)
			(size 0.450088 0.450088)
			(layers "F.Cu" "F.Mask" "F.Paste")
			(net "PVDDCR_CPU1_P1")
		)
		(pad "BP33" smd circle
			(at -4.849876 8.459978 180)
			(size 0.450088 0.450088)
			(layers "F.Cu" "F.Mask" "F.Paste")
			(net "GND")
		)
		(pad "BP34" smd circle
			(at -3.910076 8.459978 180)
			(size 0.450088 0.450088)
			(layers "F.Cu" "F.Mask" "F.Paste")
			(net "PVDDCR_CPU1_P1")
		)
		(pad "BP35" smd circle
			(at -2.970022 8.459978 180)
			(size 0.450088 0.450088)
			(layers "F.Cu" "F.Mask" "F.Paste")
			(net "GND")
		)
		(pad "BP36" smd circle
			(at -2.029968 8.459978 180)
			(size 0.450088 0.450088)
			(layers "F.Cu" "F.Mask" "F.Paste")
			(net "PVDDCR_CPU1_P1")
		)
		(pad "BP37" smd circle
			(at -1.089914 8.459978 180)
			(size 0.450088 0.450088)
			(layers "F.Cu" "F.Mask" "F.Paste")
			(net "GND")
		)
		(pad "BP39" smd circle
			(at 0.78994 8.459978 180)
			(size 0.450088 0.450088)
			(layers "F.Cu" "F.Mask" "F.Paste")
			(net "PVDDCR_CPU1_P1")
		)
		(pad "BP40" smd circle
			(at 1.729994 8.459978 180)
			(size 0.450088 0.450088)
			(layers "F.Cu" "F.Mask" "F.Paste")
			(net "GND")
		)
		(pad "BP41" smd circle
			(at 2.670048 8.459978 180)
			(size 0.450088 0.450088)
			(layers "F.Cu" "F.Mask" "F.Paste")
			(net "PVDDCR_CPU1_P1")
		)
		(pad "BP42" smd circle
			(at 3.610102 8.459978 180)
			(size 0.450088 0.450088)
			(layers "F.Cu" "F.Mask" "F.Paste")
			(net "GND")
		)
		(pad "BP43" smd circle
			(at 4.549902 8.459978 180)
			(size 0.450088 0.450088)
			(layers "F.Cu" "F.Mask" "F.Paste")
			(net "PVDDCR_CPU1_P1")
		)
		(pad "BP44" smd circle
			(at 5.489956 8.459978 180)
			(size 0.450088 0.450088)
			(layers "F.Cu" "F.Mask" "F.Paste")
			(net "GND")
		)
		(pad "BP45" smd circle
			(at 6.43001 8.459978 180)
			(size 0.450088 0.450088)
			(layers "F.Cu" "F.Mask" "F.Paste")
			(net "PVDDCR_CPU1_P1")
		)
		(pad "BP46" smd circle
			(at 7.370064 8.459978 180)
			(size 0.450088 0.450088)
			(layers "F.Cu" "F.Mask" "F.Paste")
			(net "GND")
		)
		(pad "BP47" smd circle
			(at 8.310118 8.459978 180)
			(size 0.450088 0.450088)
			(layers "F.Cu" "F.Mask" "F.Paste")
			(net "PVDDCR_CPU1_P1")
		)
		(pad "BP48" smd circle
			(at 9.249918 8.459978 180)
			(size 0.450088 0.450088)
			(layers "F.Cu" "F.Mask" "F.Paste")
			(net "GND")
		)
		(pad "BP49" smd circle
			(at 10.189972 8.459978 180)
			(size 0.450088 0.450088)
			(layers "F.Cu" "F.Mask" "F.Paste")
			(net "PVDDCR_CPU1_P1")
		)
		(pad "BP50" smd circle
			(at 11.130026 8.459978 180)
			(size 0.450088 0.450088)
			(layers "F.Cu" "F.Mask" "F.Paste")
			(net "GND")
		)
		(pad "BP51" smd circle
			(at 12.07008 8.459978 180)
			(size 0.450088 0.450088)
			(layers "F.Cu" "F.Mask" "F.Paste")
			(net "PVDD_33_S5")
		)
		(pad "BP52" smd circle
			(at 13.00988 8.459978 180)
			(size 0.450088 0.450088)
			(layers "F.Cu" "F.Mask" "F.Paste")
			(net "GND")
		)
		(pad "BP53" smd circle
			(at 13.949934 8.459978 180)
			(size 0.450088 0.450088)
			(layers "F.Cu" "F.Mask" "F.Paste")
			(net "TP_VSENSE_PVDD33_S5_P1")
		)
		(pad "BP54" smd circle
			(at 14.889988 8.459978 180)
			(size 0.450088 0.450088)
			(layers "F.Cu" "F.Mask" "F.Paste")
			(net "GND")
		)
		(pad "BP55" smd circle
			(at 15.830042 8.459978 180)
			(size 0.450088 0.450088)
			(layers "F.Cu" "F.Mask" "F.Paste")
			(net "Net_2010")
		)
		(pad "BP56" smd circle
			(at 16.770096 8.459978 180)
			(size 0.450088 0.450088)
			(layers "F.Cu" "F.Mask" "F.Paste")
			(net "M_C_CPU1_SB_RSP<0>")
		)
		(pad "BP57" smd circle
			(at 17.709896 8.459978 180)
			(size 0.450088 0.450088)
			(layers "F.Cu" "F.Mask" "F.Paste")
			(net "GND")
		)
		(pad "BP58" smd circle
			(at 18.64995 8.459978 180)
			(size 0.450088 0.450088)
			(layers "F.Cu" "F.Mask" "F.Paste")
			(net "Net_2018")
		)
		(pad "BP59" smd circle
			(at 19.590004 8.459978 180)
			(size 0.450088 0.450088)
			(layers "F.Cu" "F.Mask" "F.Paste")
			(net "GND")
		)
		(pad "BP60" smd circle
			(at 20.530058 8.459978 180)
			(size 0.450088 0.450088)
			(layers "F.Cu" "F.Mask" "F.Paste")
			(net "M_D_CPU1_SB_RSP<0>")
		)
		(pad "BP61" smd circle
			(at 21.470112 8.459978 180)
			(size 0.450088 0.450088)
			(layers "F.Cu" "F.Mask" "F.Paste")
			(net "GND")
		)
		(pad "BP62" smd circle
			(at 22.409912 8.459978 180)
			(size 0.450088 0.450088)
			(layers "F.Cu" "F.Mask" "F.Paste")
			(net "Net_2002")
		)
		(pad "BP63" smd circle
			(at 23.349966 8.459978 180)
			(size 0.450088 0.450088)
			(layers "F.Cu" "F.Mask" "F.Paste")
			(net "M_B_CPU1_SB_RSP<0>")
		)
		(pad "BP64" smd circle
			(at 24.29002 8.459978 180)
			(size 0.450088 0.450088)
			(layers "F.Cu" "F.Mask" "F.Paste")
			(net "GND")
		)
		(pad "BP65" smd circle
			(at 25.230074 8.459978 180)
			(size 0.450088 0.450088)
			(layers "F.Cu" "F.Mask" "F.Paste")
			(net "Net_2034")
		)
		(pad "BP66" smd circle
			(at 26.170128 8.459978 180)
			(size 0.450088 0.450088)
			(layers "F.Cu" "F.Mask" "F.Paste")
			(net "GND")
		)
		(pad "BP67" smd circle
			(at 27.109928 8.459978 180)
			(size 0.450088 0.450088)
			(layers "F.Cu" "F.Mask" "F.Paste")
			(net "M_F_CPU1_SB_RSP<0>")
		)
		(pad "BP68" smd circle
			(at 28.049982 8.459978 180)
			(size 0.450088 0.450088)
			(layers "F.Cu" "F.Mask" "F.Paste")
			(net "GND")
		)
		(pad "BP69" smd circle
			(at 28.990036 8.459978 180)
			(size 0.450088 0.450088)
			(layers "F.Cu" "F.Mask" "F.Paste")
			(net "Net_2026")
		)
		(pad "BP70" smd circle
			(at 29.93009 8.459978 180)
			(size 0.450088 0.450088)
			(layers "F.Cu" "F.Mask" "F.Paste")
			(net "M_E_CPU1_SB_RSP<0>")
		)
		(pad "BP71" smd circle
			(at 30.86989 8.459978 180)
			(size 0.450088 0.450088)
			(layers "F.Cu" "F.Mask" "F.Paste")
			(net "GND")
		)
		(pad "BP72" smd circle
			(at 31.809944 8.459978 180)
			(size 0.450088 0.450088)
			(layers "F.Cu" "F.Mask" "F.Paste")
			(net "Net_1994")
		)
		(pad "BP73" smd circle
			(at 32.749998 8.459978 180)
			(size 0.450088 0.450088)
			(layers "F.Cu" "F.Mask" "F.Paste")
			(net "GND")
		)
		(pad "BP74" smd circle
			(at 33.690052 8.459978 180)
			(size 0.450088 0.450088)
			(layers "F.Cu" "F.Mask" "F.Paste")
			(net "M_A_CPU1_SB_RSP<0>")
		)
		(pad "BR1" smd circle
			(at -34.459926 9.269984 180)
			(size 0.450088 0.450088)
			(layers "F.Cu" "F.Mask" "F.Paste")
			(net "GND")
		)
		(pad "BR2" smd circle
			(at -33.519872 9.269984 180)
			(size 0.450088 0.450088)
			(layers "F.Cu" "F.Mask" "F.Paste")
			(net "Net_2045")
		)
		(pad "BR3" smd circle
			(at -32.580072 9.269984 180)
			(size 0.450088 0.450088)
			(layers "F.Cu" "F.Mask" "F.Paste")
			(net "GND")
		)
		(pad "BR4" smd circle
			(at -31.640018 9.269984 180)
			(size 0.450088 0.450088)
			(layers "F.Cu" "F.Mask" "F.Paste")
			(net "PVDD11_S3_P1")
		)
		(pad "BR5" smd circle
			(at -30.699964 9.269984 180)
			(size 0.450088 0.450088)
			(layers "F.Cu" "F.Mask" "F.Paste")
			(net "Net_2194")
		)
		(pad "BR6" smd circle
			(at -29.75991 9.269984 180)
			(size 0.450088 0.450088)
			(layers "F.Cu" "F.Mask" "F.Paste")
			(net "GND")
		)
		(pad "BR7" smd circle
			(at -28.82011 9.269984 180)
			(size 0.450088 0.450088)
			(layers "F.Cu" "F.Mask" "F.Paste")
			(net "GND")
		)
		(pad "BR8" smd circle
			(at -27.880056 9.269984 180)
			(size 0.450088 0.450088)
			(layers "F.Cu" "F.Mask" "F.Paste")
			(net "GND")
		)
		(pad "BR9" smd circle
			(at -26.940002 9.269984 180)
			(size 0.450088 0.450088)
			(layers "F.Cu" "F.Mask" "F.Paste")
			(net "Net_2186")
		)
		(pad "BR10" smd circle
			(at -25.999948 9.269984 180)
			(size 0.450088 0.450088)
			(layers "F.Cu" "F.Mask" "F.Paste")
			(net "GND")
		)
		(pad "BR11" smd circle
			(at -25.059894 9.269984 180)
			(size 0.450088 0.450088)
			(layers "F.Cu" "F.Mask" "F.Paste")
			(net "PVDD11_S3_P1")
		)
		(pad "BR12" smd circle
			(at -24.120094 9.269984 180)
			(size 0.450088 0.450088)
			(layers "F.Cu" "F.Mask" "F.Paste")
			(net "Net_2053")
		)
		(pad "BR13" smd circle
			(at -23.18004 9.269984 180)
			(size 0.450088 0.450088)
			(layers "F.Cu" "F.Mask" "F.Paste")
			(net "GND")
		)
		(pad "BR14" smd circle
			(at -22.239986 9.269984 180)
			(size 0.450088 0.450088)
			(layers "F.Cu" "F.Mask" "F.Paste")
			(net "GND")
		)
		(pad "BR15" smd circle
			(at -21.299932 9.269984 180)
			(size 0.450088 0.450088)
			(layers "F.Cu" "F.Mask" "F.Paste")
			(net "GND")
		)
		(pad "BR16" smd circle
			(at -20.359878 9.269984 180)
			(size 0.450088 0.450088)
			(layers "F.Cu" "F.Mask" "F.Paste")
			(net "Net_2069")
		)
		(pad "BR17" smd circle
			(at -19.420078 9.269984 180)
			(size 0.450088 0.450088)
			(layers "F.Cu" "F.Mask" "F.Paste")
			(net "GND")
		)
		(pad "BR18" smd circle
			(at -18.480024 9.269984 180)
			(size 0.450088 0.450088)
			(layers "F.Cu" "F.Mask" "F.Paste")
			(net "PVDD11_S3_P1")
		)
		(pad "BR19" smd circle
			(at -17.53997 9.269984 180)
			(size 0.450088 0.450088)
			(layers "F.Cu" "F.Mask" "F.Paste")
			(net "Net_2061")
		)
		(pad "BR20" smd circle
			(at -16.599916 9.269984 180)
			(size 0.450088 0.450088)
			(layers "F.Cu" "F.Mask" "F.Paste")
			(net "GND")
		)
		(pad "BR21" smd circle
			(at -15.660116 9.269984 180)
			(size 0.450088 0.450088)
			(layers "F.Cu" "F.Mask" "F.Paste")
			(net "GND")
		)
		(pad "BR22" smd circle
			(at -14.720062 9.269984 180)
			(size 0.450088 0.450088)
			(layers "F.Cu" "F.Mask" "F.Paste")
			(net "GND")
		)
		(pad "BR23" smd circle
			(at -13.780008 9.269984 180)
			(size 0.450088 0.450088)
			(layers "F.Cu" "F.Mask" "F.Paste")
			(net "PVDDCR_CPU1_P1")
		)
		(pad "BR24" smd circle
			(at -12.839954 9.269984 180)
			(size 0.450088 0.450088)
			(layers "F.Cu" "F.Mask" "F.Paste")
			(net "GND")
		)
		(pad "BR25" smd circle
			(at -11.8999 9.269984 180)
			(size 0.450088 0.450088)
			(layers "F.Cu" "F.Mask" "F.Paste")
			(net "PVDDCR_CPU1_P1")
		)
		(pad "BR26" smd circle
			(at -10.9601 9.269984 180)
			(size 0.450088 0.450088)
			(layers "F.Cu" "F.Mask" "F.Paste")
			(net "GND")
		)
		(pad "BR27" smd circle
			(at -10.020046 9.269984 180)
			(size 0.450088 0.450088)
			(layers "F.Cu" "F.Mask" "F.Paste")
			(net "PVDDCR_CPU1_P1")
		)
		(pad "BR28" smd circle
			(at -9.079992 9.269984 180)
			(size 0.450088 0.450088)
			(layers "F.Cu" "F.Mask" "F.Paste")
			(net "GND")
		)
		(pad "BR29" smd circle
			(at -8.139938 9.269984 180)
			(size 0.450088 0.450088)
			(layers "F.Cu" "F.Mask" "F.Paste")
			(net "PVDDCR_CPU1_P1")
		)
	)
)
